FILE_TYPE = CONNECTIVITY;
{Allegro Design Entry HDL 17.2-2016 S067 (3860444) 4/26/2020}
"PAGE_NUMBER" = 20;
0"NC";
END.
